FILE_TYPE = MACRO_DRAWING;
SET COLOR_WIRE YELLOW;
SET COLOR_PROP ORANGE;
SET COLOR_DOT WHITE;
SET COLOR_ARC YELLOW;
SET COLOR_BODY GREEN;
SET COLOR_NOTE PURPLE;
SET PROP_DISPLAY VALUE;
SET PAGE_NUMBER P8;
FORCEADD QUANTA_TITLE_BLOCK_C..1
(-100 100);
FORCEPROP 1 LAST CUSTOM_TXT_CDS <NAME_2>
J 0
(-3275 150);
FORCEPROP 1 LAST CUSTOM_TXT_CDS <NAME_1>
J 0
(-3275 275);
FORCEPROP 1 LAST CUSTOM_TXT_CDS <Q_NUMBER>
J 0
(-1503 203);
DISPLAY 1.212766 (-1503 203);
FORCEPROP 1 LAST CUSTOM_TXT_CDS <Q_PROJ>
J 0
(-2482 202);
DISPLAY 1.212766 (-2482 202);
FORCEPROP 1 LAST CUSTOM_TXT_CDS <Q_REV>
J 0
(-284 203);
DISPLAY 1.212766 (-284 203);
FORCEPROP 1 LAST CUSTOM_TXT_CDS <CON_LAST_MODIFIED>
J 0
(-1985 115);
DISPLAY 0.978723 (-1985 115);
FORCEPROP 1 LAST CUSTOM_TXT_CDS <CON_PAGE_NUM> OF <CON_TOTAL_PAGES>
J 0
(-546 118);
DISPLAY 0.978723 (-546 118);
FORCEPROP 1 LAST Q_DEPT BU9
J 1
(-3863 149);
DISPLAY 1.957447 (-3863 149);
PAINT GREEN (-3863 149);
FORCEPROP 1 LAST Q_TITLE BLOCK DIAGRAM - I2C/I3C
J 0
(-9375 175);
DISPLAY 2.446809 (-9375 175);
PAINT GREEN (-9375 175);
FORCEPROP 1 LAST COMMENT_BODY TRUE
J 0
(-88 87);
DISPLAY 0.978723 (-88 87);
PAINT GREEN (-88 87);
DISPLAY INVISIBLE (-88 87);
FORCEPROP 2 LAST PAGE_BORDER TRUE
J 0
(-7990 5350);
DISPLAY 0.638298 (-7990 5350);
PAINT PINK (-7990 5350);
DISPLAY INVISIBLE (-7990 5350);
FORCEPROP 2 LAST CDS_LIB pure_quanta
J 0
(-100 100);
DISPLAY INVISIBLE (-100 100);
FORCEPROP 1 LAST CDS_LMAN_SYM_OUTLINE -9475,6775,100,-125
J 0
(-100 100);
DISPLAY 0.468085 (-100 100);
PAINT GREEN (-100 100);
DISPLAY INVISIBLE (-100 100);
FORCEPROP 2 LAST CDS_XR_PAGE_TITLE CR-8 : @T6G_MB_LIB.T6G(SCH_1):PAGE8
J 0
(-7990 5350);
DISPLAY 0.638298 (-7990 5350);
PAINT PINK (-7990 5350);
DISPLAY INVISIBLE (-7990 5350);
FORCEPROP 2 LAST CUSTOM_TXT_CDS <XR_PAGE_TITLE>
J 0
(-7990 5350);
DISPLAY 0.638298 (-7990 5350);
PAINT PINK (-7990 5350);
DISPLAY INVISIBLE (-7990 5350);
FORCEPROP 0 LAST CDS_CON_LAST_MODIFIED Tue Mar 08 15:46:35 2022
J 0
(-1985 115);
DISPLAY INVISIBLE (-1985 115);
QUIT
